FILE_TYPE = CONNECTIVITY;
{Allegro Design Entry HDL 17.4-2019 S026 (4007227) 1/17/2022}
"PAGE_NUMBER" = 412;
0"NC";
END.
